# T6G (Grand Teton) — schematic netlist excerpt (pin names and nets, part order shuffled) for the footprints in the layout excerpt that follows; sources: Cadence DE-HDL packaged netlist, KiCad conversion of 04192023_DAF0TMB3IC0_F0TG_MB_C_brd_V02_OCP.brd

PU26  ISL99390FRZTR5935  ISL99390FRZ-TR5935 IC  pkg QFN21_6X5XB  page 211
  VOS  = PVDDCR_CPU0_P1_VOS2
  AGND  = GND
  VCC  = PVDDCR_CPU0_P1_VCC2
  PVCC  = PVDDCR_CPU0_P1_PVCC
  PGND1  = GND
  GL1  = NC_PVDDCR_CPU0_P1_GL1_2
  PGND2  = GND
  SW  = SW_PVDDCR_CPU0_P1_SW2
  VIN1  = SW_P12V_AUX_PVDDCR_CPU0_P1_FLT
  VIN2  = SW_P12V_AUX_PVDDCR_CPU0_P1_FLT
  DNC  = NC_PVDDCR_CPU0_P1_DNC2
  PHASE  = SW_PVDDCR_CPU0_P1_PH2
  BOOT  = SW_PVDDCR_CPU0_P1_BOOT2
  PWM  = PVDDCR_CPU0_P1_PWM2
  EN  = PVDDCR_CPU0_P1_VCC2
  TOUT_FLT  = PVDDCR_CPU0_P1_TEMP0
  LSET  = PVDDCR_CPU0_P1_LSET2
  IOUT  = PVDDCR_CPU0_P1_IMON2
  REFIN  = PVDDCR_CPU0_P1_VCCS
  PGND3  = GND
  GL2  = NC_PVDDCR_CPU0_P1_GL2_2

(kicad_pcb
	(version 20260206)
	(generator "pcbnew")
	(generator_version "10.0")
	(general
		(thickness 1.6)
		(legacy_teardrops no)
	)
	(paper "A4")
	(title_block
		(title "04192023_DAF0TMB3IC0_F0TG_MB_C_brd_V02_OCP.brd")
		(comment 1 "Grand Teton / footprints 2297-2297 of 8354")
	)
	(layers
		(0 "F.Cu" signal "TOP")
		(4 "In1.Cu" signal "GND")
		(6 "In2.Cu" signal "IN1")
		(8 "In3.Cu" signal "GND1")
		(10 "In4.Cu" signal "IN2")
		(12 "In5.Cu" signal "GND2")
		(14 "In6.Cu" signal "IN3")
		(16 "In7.Cu" signal "GND3")
		(18 "In8.Cu" signal "VCC")
		(20 "In9.Cu" signal "VCC1")
		(22 "In10.Cu" signal "GND4")
		(24 "In11.Cu" signal "IN4")
		(26 "In12.Cu" signal "GND5")
		(28 "In13.Cu" signal "IN5")
		(30 "In14.Cu" signal "GND6")
		(32 "In15.Cu" signal "IN6")
		(34 "In16.Cu" signal "GND7")
		(2 "B.Cu" signal "BOTTOM")
		(9 "F.Adhes" user "F.Adhesive")
		(11 "B.Adhes" user "B.Adhesive")
		(13 "F.Paste" user "Package Geometry/Pastemask Top")
		(15 "B.Paste" user "Package Geometry/Pastemask Bottom")
		(5 "F.SilkS" user "Ref Des/Silkscreen Top")
		(7 "B.SilkS" user "Ref Des/Silkscreen Bottom")
		(1 "F.Mask" user "Board Geometry/Soldermask Top")
		(3 "B.Mask" user "Board Geometry/Soldermask Bottom")
		(17 "Dwgs.User" user "User.Drawings")
		(19 "Cmts.User" user "User.Comments")
		(21 "Eco1.User" user "User.Eco1")
		(23 "Eco2.User" user "User.Eco2")
		(25 "Edge.Cuts" user "Board Geometry/Outline")
		(27 "Margin" user)
		(31 "F.CrtYd" user "Package Geometry/Place Bound Top")
		(29 "B.CrtYd" user "Package Geometry/Place Bound Bottom")
		(35 "F.Fab" user "Ref Des/Assembly Top")
		(33 "B.Fab" user "Ref Des/Assembly Bottom")
	)
	(footprint ""
		(layer "F.Cu")
		(at 90.68181 -182.675784 180)
		(property "Reference" "PU26"
			(at -0.51816 -6.641338 0)
			(unlocked yes)
			(layer "F.SilkS")
			(effects
				(font
					(size 0.7874 0.5842)
					(thickness 0.1524)
				)
				(justify left)
			)
		)
		(property "Value" ""
			(at 0 0 180)
			(layer "F.Fab")
			(effects
				(font
					(size 1.27 1.27)
				)
			)
		)
		(duplicate_pad_numbers_are_jumpers no)
		(fp_line
			(start 2.500122 2.999994)
			(end 2.2987 2.999994)
			(stroke
				(width 0.1524)
				(type default)
			)
			(layer "F.SilkS")
		)
		(fp_line
			(start 2.500122 2.339594)
			(end 2.500122 2.999994)
			(stroke
				(width 0.1524)
				(type default)
			)
			(layer "F.SilkS")
		)
		(fp_line
			(start 2.500122 -2.999994)
			(end 2.500122 -2.44348)
			(stroke
				(width 0.1524)
				(type default)
			)
			(layer "F.SilkS")
		)
		(fp_line
			(start 2.31394 -2.999994)
			(end 2.500122 -2.999994)
			(stroke
				(width 0.1524)
				(type default)
			)
			(layer "F.SilkS")
		)
		(fp_line
			(start -2.2987 2.999994)
			(end -2.500122 2.999994)
			(stroke
				(width 0.1524)
				(type default)
			)
			(layer "F.SilkS")
		)
		(fp_line
			(start -2.500122 2.999994)
			(end -2.500122 2.339594)
			(stroke
				(width 0.1524)
				(type default)
			)
			(layer "F.SilkS")
		)
		(fp_line
			(start -2.500122 0.6604)
			(end -2.500122 0.229108)
			(stroke
				(width 0.1524)
				(type default)
			)
			(layer "F.SilkS")
		)
		(fp_line
			(start -2.500122 -2.529078)
			(end -2.500122 -2.999994)
			(stroke
				(width 0.1524)
				(type default)
			)
			(layer "F.SilkS")
		)
		(fp_line
			(start -2.500122 -2.999994)
			(end -2.24409 -2.999994)
			(stroke
				(width 0.1524)
				(type default)
			)
			(layer "F.SilkS")
		)
		(fp_poly
			(pts
				(xy -2.708148 -2.422144) (xy -3.381756 -2.64668) (xy -2.932684 -3.095752)
			)
			(stroke
				(width 0)
				(type default)
			)
			(fill yes)
			(layer "F.SilkS")
		)
		(fp_line
			(start 2.500122 2.999994)
			(end -2.500122 2.999994)
			(stroke
				(width 0.1)
				(type default)
			)
			(layer "F.Fab")
		)
		(fp_line
			(start 2.500122 -2.999994)
			(end 2.500122 2.999994)
			(stroke
				(width 0.1)
				(type default)
			)
			(layer "F.Fab")
		)
		(fp_line
			(start -2.500122 2.999994)
			(end -2.500122 -2.999994)
			(stroke
				(width 0.1)
				(type default)
			)
			(layer "F.Fab")
		)
		(fp_line
			(start -2.500122 -2.999994)
			(end 2.500122 -2.999994)
			(stroke
				(width 0.1)
				(type default)
			)
			(layer "F.Fab")
		)
		(fp_poly
			(pts
				(xy -4.218432 -2.783078) (xy -4.218432 -1.767078) (xy -3.202432 -2.275078)
			)
			(stroke
				(width 0)
				(type default)
			)
			(fill yes)
			(layer "F.Fab")
		)
		(pad "1" smd rect
			(at -2.400046 -2.275078 270)
			(size 0.2286 0.6096)
			(layers "F.Cu" "F.Mask" "F.Paste")
			(net "PVDDCR_CPU0_P1_VOS2")
		)
		(pad "2" smd rect
			(at -2.400046 -1.82499 270)
			(size 0.2286 0.6096)
			(layers "F.Cu" "F.Mask" "F.Paste")
			(net "GND")
		)
		(pad "3" smd rect
			(at -2.400046 -1.374902 270)
			(size 0.2286 0.6096)
			(layers "F.Cu" "F.Mask" "F.Paste")
			(net "PVDDCR_CPU0_P1_VCC2")
		)
		(pad "4" smd rect
			(at -2.400046 -0.925068 270)
			(size 0.2286 0.6096)
			(layers "F.Cu" "F.Mask" "F.Paste")
			(net "PVDDCR_CPU0_P1_PVCC")
		)
		(pad "5" smd rect
			(at -2.400046 -0.47498 270)
			(size 0.2286 0.6096)
			(layers "F.Cu" "F.Mask" "F.Paste")
			(net "GND")
		)
		(pad "6" smd rect
			(at -2.400046 -0.024892 270)
			(size 0.2286 0.6096)
			(layers "F.Cu" "F.Mask" "F.Paste")
			(net "NC_PVDDCR_CPU0_P1_GL1_2")
		)
		(pad "7_9-20_24" smd circle
			(at 0 1.150112 270)
			(size 0 0)
			(layers "F.Cu" "F.Mask" "F.Paste")
			(net "GND")
		)
		(pad "10_19" smd rect
			(at 0 2.899918 270)
			(size 0.6096 4.318)
			(layers "F.Cu" "F.Mask" "F.Paste")
			(net "SW_PVDDCR_CPU0_P1_SW2")
		)
		(pad "25_29" smd rect
			(at 1.549908 -1.279906 90)
			(size 2.0574 2.3114)
			(layers "F.Cu" "F.Mask" "F.Paste")
			(net "SW_P12V_AUX_PVDDCR_CPU0_P1_FLT")
		)
		(pad "30" smd rect
			(at 2.05994 -2.899918 180)
			(size 0.2286 0.6096)
			(layers "F.Cu" "F.Mask" "F.Paste")
			(net "SW_P12V_AUX_PVDDCR_CPU0_P1_FLT")
		)
		(pad "31" smd rect
			(at 1.610106 -2.899918 180)
			(size 0.2286 0.6096)
			(layers "F.Cu" "F.Mask" "F.Paste")
			(net "NC_PVDDCR_CPU0_P1_DNC2")
		)
		(pad "32" smd rect
			(at 1.160018 -2.899918 180)
			(size 0.2286 0.6096)
			(layers "F.Cu" "F.Mask" "F.Paste")
			(net "SW_PVDDCR_CPU0_P1_PH2")
		)
		(pad "33" smd rect
			(at 0.70993 -2.899918 180)
			(size 0.2286 0.6096)
			(layers "F.Cu" "F.Mask" "F.Paste")
			(net "SW_PVDDCR_CPU0_P1_BOOT2")
		)
		(pad "34" smd rect
			(at 0.260096 -2.899918 180)
			(size 0.2286 0.6096)
			(layers "F.Cu" "F.Mask" "F.Paste")
			(net "PVDDCR_CPU0_P1_PWM2")
		)
		(pad "35" smd rect
			(at -0.189992 -2.899918 180)
			(size 0.2286 0.6096)
			(layers "F.Cu" "F.Mask" "F.Paste")
			(net "PVDDCR_CPU0_P1_VCC2")
		)
		(pad "36" smd rect
			(at -0.64008 -2.899918 180)
			(size 0.2286 0.6096)
			(layers "F.Cu" "F.Mask" "F.Paste")
			(net "PVDDCR_CPU0_P1_TEMP0")
		)
		(pad "37" smd rect
			(at -1.089914 -2.899918 180)
			(size 0.2286 0.6096)
			(layers "F.Cu" "F.Mask" "F.Paste")
			(net "PVDDCR_CPU0_P1_LSET2")
		)
		(pad "38" smd rect
			(at -1.540002 -2.899918 180)
			(size 0.2286 0.6096)
			(layers "F.Cu" "F.Mask" "F.Paste")
			(net "PVDDCR_CPU0_P1_IMON2")
		)
		(pad "39" smd rect
			(at -1.99009 -2.899918 180)
			(size 0.2286 0.6096)
			(layers "F.Cu" "F.Mask" "F.Paste")
			(net "PVDDCR_CPU0_P1_VCCS")
		)
		(pad "40" smd rect
			(at -0.87503 -1.27508 180)
			(size 1.7526 1.9558)
			(layers "F.Cu" "F.Mask" "F.Paste")
			(net "GND")
		)
		(pad "41" smd rect
			(at -1.525016 0.249936 90)
			(size 0.3048 0.4572)
			(layers "F.Cu" "F.Mask" "F.Paste")
			(net "NC_PVDDCR_CPU0_P1_GL2_2")
		)
		(zone
			(layer "F.Cu")
			(hatch none 0.5)
			(connect_pads
				(clearance 0)
			)
			(min_thickness 0.25)
			(keepout
				(tracks not_allowed)
				(vias allowed)
				(pads allowed)
				(copperpour not_allowed)
				(footprints allowed)
			)
			(placement
				(enabled no)
				(sheetname "")
			)
			(fill
				(thermal_gap 0.5)
				(thermal_bridge_width 0.5)
				(island_removal_mode 0)
			)
			(polygon
				(pts
					(xy 93.181932 -185.220102) (xy 93.181932 -184.926478) (xy 88.181688 -184.926478) (xy 88.181688 -185.220102)
					(xy 88.47201 -185.220102) (xy 92.89161 -185.220102)
				)
			)
		)
		(zone
			(layer "F.Cu")
			(hatch none 0.5)
			(connect_pads
				(clearance 0)
			)
			(min_thickness 0.25)
			(keepout
				(tracks not_allowed)
				(vias allowed)
				(pads allowed)
				(copperpour not_allowed)
				(footprints allowed)
			)
			(placement
				(enabled no)
				(sheetname "")
			)
			(fill
				(thermal_gap 0.5)
				(thermal_bridge_width 0.5)
				(island_removal_mode 0)
			)
			(polygon
				(pts
					(xy 90.62974 -182.429404) (xy 90.62974 -180.372004) (xy 92.48394 -180.372004) (xy 92.48394 -180.61305)
					(xy 92.726256 -180.61305) (xy 92.726256 -180.131466) (xy 88.825578 -180.131466) (xy 88.825578 -180.316378)
					(xy 90.338402 -180.316378) (xy 90.338402 -182.475378) (xy 88.181688 -182.475378) (xy 88.181688 -182.72506)
					(xy 90.334084 -182.72506)
				)
			)
		)
	)
)
